FILE_TYPE = MULTI_PHYS_TABLE;
PART 'TMP421'
{===============================================================================================================================================================================================================}
:PACK_TYPE | MATERIAL | PART_NUMBER     = EnvComp | PART_NUMBER  | JEDEC_TYPE        | DESCRIPTION                     | CLASS | COMPONENT_TYPE | HEIGHT     | LPID  |SPEED_URL | Status |RPL| AML | Bus_Unit | Days ;
{===============================================================================================================================================================================================================}
'TSSOP'    | 'IC'     | 'G62962-001'(!) = 'YES;YES;YES;UNK;ok;VLD' | 'G62962-001' | 'TSSOP8_7_65MB'   | 'IC,TEMP SENSOR,SOT23-8,TMP421' | 'IC'  | 'SMALLSMT'     | '0.057 IN' |'2407' |'http://speed.intel.com:8081/speed/module/pdm/item/pdm_item_detail_direct.asp?item_cde=G62962-001&item_rev=01&url_param=unused' | 'Design' | 'YES' | '1' | 'SMO_IC' | '???' 
'TSSOP'    | 'EMPTY'  | 'G62962-001'(!) = 'YES;YES;YES;UNK;ok;VLD' | 'G62962-001' | 'TSSOP8_7_65MB'   | 'IC,TEMP SENSOR,SOT23-8,TMP421' | 'IO'  | 'SMALLSMT'     | '0.057 IN' |'2407' |'http://speed.intel.com:8081/speed/module/pdm/item/pdm_item_detail_direct.asp?item_cde=G62962-001&item_rev=01&url_param=unused' | 'Design' | 'YES' | '1' | 'SMO_IC' | '???' 
END_PART
END.
